(kicad_pcb
	(version 20260206)
	(generator "pcbnew")
	(generator_version "10.0")
	(general
		(thickness 1.6)
		(legacy_teardrops no)
	)
	(paper "A4")
	(title_block
		(title "12092022_DA0F0TMDCD0_F0T_Management_Board_D_brd_V3_OCP.brd")
		(comment 1 "Grand Teton / footprints 56-60 of 1440")
	)
	(layers
		(0 "F.Cu" signal "TOP")
		(4 "In1.Cu" signal "GND")
		(6 "In2.Cu" signal "IN1")
		(8 "In3.Cu" signal "GND1")
		(10 "In4.Cu" signal "IN2")
		(12 "In5.Cu" signal "VCC")
		(14 "In6.Cu" signal "VCC1")
		(16 "In7.Cu" signal "IN3")
		(18 "In8.Cu" signal "GND2")
		(20 "In9.Cu" signal "IN4")
		(22 "In10.Cu" signal "GND3")
		(2 "B.Cu" signal "BOTTOM")
		(9 "F.Adhes" user "F.Adhesive")
		(11 "B.Adhes" user "B.Adhesive")
		(13 "F.Paste" user "Package Geometry/Pastemask Top")
		(15 "B.Paste" user "Package Geometry/Pastemask Bottom")
		(5 "F.SilkS" user "Ref Des/Silkscreen Top")
		(7 "B.SilkS" user "Ref Des/Silkscreen Bottom")
		(1 "F.Mask" user "Board Geometry/Soldermask Top")
		(3 "B.Mask" user "Board Geometry/Soldermask Bottom")
		(17 "Dwgs.User" user "User.Drawings")
		(19 "Cmts.User" user "User.Comments")
		(21 "Eco1.User" user "User.Eco1")
		(23 "Eco2.User" user "User.Eco2")
		(25 "Edge.Cuts" user "Board Geometry/Outline")
		(27 "Margin" user)
		(31 "F.CrtYd" user "Package Geometry/Place Bound Top")
		(29 "B.CrtYd" user "Package Geometry/Place Bound Bottom")
		(35 "F.Fab" user "Ref Des/Assembly Top")
		(33 "B.Fab" user "Ref Des/Assembly Bottom")
	)
	(footprint ""
		(layer "F.Cu")
		(at 95.926656 -98.400362 -90)
		(property "Reference" "J26"
			(at -3.961638 -1.509014 90)
			(unlocked yes)
			(layer "F.SilkS")
			(effects
				(font
					(size 0.7874 0.5842)
					(thickness 0.1524)
				)
				(justify left)
			)
		)
		(property "Value" ""
			(at 0 0 270)
			(layer "F.Fab")
			(effects
				(font
					(size 1.27 1.27)
				)
			)
		)
		(duplicate_pad_numbers_are_jumpers no)
		(fp_line
			(start -1.2192 2.1082)
			(end -1.2192 -2.1082)
			(stroke
				(width 0.1524)
				(type default)
			)
			(layer "F.SilkS")
		)
		(fp_line
			(start 1.2192 2.1082)
			(end -1.2192 2.1082)
			(stroke
				(width 0.1524)
				(type default)
			)
			(layer "F.SilkS")
		)
		(fp_line
			(start 1.2192 0.80137)
			(end 1.2192 2.1082)
			(stroke
				(width 0.1524)
				(type default)
			)
			(layer "F.SilkS")
		)
		(fp_line
			(start -1.2192 -2.1082)
			(end 1.2192 -2.1082)
			(stroke
				(width 0.1524)
				(type default)
			)
			(layer "F.SilkS")
		)
		(fp_line
			(start 1.2192 -2.1082)
			(end 1.2192 -0.816102)
			(stroke
				(width 0.1524)
				(type default)
			)
			(layer "F.SilkS")
		)
		(pad "" np_thru_hole circle
			(at -2.8829 -1.27 180)
			(size 1.0414 1.0414)
			(drill 1.0414)
			(layers "*.Cu" "*.Mask")
			(clearance 0.381)
			(thermal_gap 0.381)
		)
		(pad "" np_thru_hole circle
			(at -2.8829 1.27 180)
			(size 1.0414 1.0414)
			(drill 1.0414)
			(layers "*.Cu" "*.Mask")
			(clearance 0.381)
			(thermal_gap 0.381)
		)
		(pad "" np_thru_hole circle
			(at 3.4671 -1.27 180)
			(size 1.0414 1.0414)
			(drill 1.0414)
			(layers "*.Cu" "*.Mask")
			(clearance 0.381)
			(thermal_gap 0.381)
		)
		(pad "" np_thru_hole circle
			(at 3.4671 1.27 180)
			(size 1.0414 1.0414)
			(drill 1.0414)
			(layers "*.Cu" "*.Mask")
			(clearance 0.381)
			(thermal_gap 0.381)
		)
		(pad "1" smd rect
			(at 0.8255 -0.249936 180)
			(size 0.3048 0.508)
			(layers "F.Cu" "F.Mask" "F.Paste")
			(net "85_10INCH_IN4_DN")
		)
		(pad "2" smd rect
			(at 0.8255 0.249936 180)
			(size 0.3048 0.508)
			(layers "F.Cu" "F.Mask" "F.Paste")
			(net "85_10INCH_IN4_DP")
		)
		(pad "3" smd circle
			(at 0 0 270)
			(size 0 0)
			(layers "F.Cu" "F.Mask" "F.Paste")
			(net "GND_P1")
		)
		(zone
			(layer "F.Cu")
			(hatch none 0.5)
			(connect_pads
				(clearance 0)
			)
			(min_thickness 0.25)
			(keepout
				(tracks not_allowed)
				(vias allowed)
				(pads allowed)
				(copperpour not_allowed)
				(footprints allowed)
			)
			(placement
				(enabled no)
				(sheetname "")
			)
			(fill
				(thermal_gap 0.5)
				(thermal_bridge_width 0.5)
				(island_removal_mode 0)
			)
			(polygon
				(pts
					(xy 96.475296 -97.282762) (xy 96.379792 -97.282762) (xy 96.379792 -97.879662) (xy 95.973392 -97.879662)
					(xy 95.973392 -97.282762) (xy 95.87992 -97.282762) (xy 95.87992 -97.879662) (xy 95.47352 -97.879662)
					(xy 95.47352 -97.282762) (xy 95.378016 -97.282762) (xy 95.378016 -97.981262) (xy 96.475296 -97.981262)
				)
			)
		)
		(zone
			(layers "F.Cu" "B.Cu" "In1.Cu" "In2.Cu" "In3.Cu" "In4.Cu" "In5.Cu" "In6.Cu"
				"In7.Cu" "In8.Cu" "In9.Cu" "In10.Cu"
			)
			(hatch none 0.5)
			(connect_pads
				(clearance 0)
			)
			(min_thickness 0.25)
			(keepout
				(tracks not_allowed)
				(vias allowed)
				(pads allowed)
				(copperpour not_allowed)
				(footprints allowed)
			)
			(placement
				(enabled no)
				(sheetname "")
			)
			(fill
				(thermal_gap 0.5)
				(thermal_bridge_width 0.5)
				(island_removal_mode 0)
			)
			(polygon
				(pts
					(arc
						(start 95.583756 -101.283262)
						(mid 93.729556 -101.283262)
						(end 95.583756 -101.283262)
					)
				)
			)
		)
		(zone
			(layers "F.Cu" "B.Cu" "In1.Cu" "In2.Cu" "In3.Cu" "In4.Cu" "In5.Cu" "In6.Cu"
				"In7.Cu" "In8.Cu" "In9.Cu" "In10.Cu"
			)
			(hatch none 0.5)
			(connect_pads
				(clearance 0)
			)
			(min_thickness 0.25)
			(keepout
				(tracks not_allowed)
				(vias allowed)
				(pads allowed)
				(copperpour not_allowed)
				(footprints allowed)
			)
			(placement
				(enabled no)
				(sheetname "")
			)
			(fill
				(thermal_gap 0.5)
				(thermal_bridge_width 0.5)
				(island_removal_mode 0)
			)
			(polygon
				(pts
					(arc
						(start 95.583756 -94.933262)
						(mid 93.729556 -94.933262)
						(end 95.583756 -94.933262)
					)
				)
			)
		)
		(zone
			(layers "F.Cu" "B.Cu" "In1.Cu" "In2.Cu" "In3.Cu" "In4.Cu" "In5.Cu" "In6.Cu"
				"In7.Cu" "In8.Cu" "In9.Cu" "In10.Cu"
			)
			(hatch none 0.5)
			(connect_pads
				(clearance 0)
			)
			(min_thickness 0.25)
			(keepout
				(tracks not_allowed)
				(vias allowed)
				(pads allowed)
				(copperpour not_allowed)
				(footprints allowed)
			)
			(placement
				(enabled no)
				(sheetname "")
			)
			(fill
				(thermal_gap 0.5)
				(thermal_bridge_width 0.5)
				(island_removal_mode 0)
			)
			(polygon
				(pts
					(arc
						(start 98.123756 -101.283262)
						(mid 96.269556 -101.283262)
						(end 98.123756 -101.283262)
					)
				)
			)
		)
		(zone
			(layers "F.Cu" "B.Cu" "In1.Cu" "In2.Cu" "In3.Cu" "In4.Cu" "In5.Cu" "In6.Cu"
				"In7.Cu" "In8.Cu" "In9.Cu" "In10.Cu"
			)
			(hatch none 0.5)
			(connect_pads
				(clearance 0)
			)
			(min_thickness 0.25)
			(keepout
				(tracks not_allowed)
				(vias allowed)
				(pads allowed)
				(copperpour not_allowed)
				(footprints allowed)
			)
			(placement
				(enabled no)
				(sheetname "")
			)
			(fill
				(thermal_gap 0.5)
				(thermal_bridge_width 0.5)
				(island_removal_mode 0)
			)
			(polygon
				(pts
					(arc
						(start 98.123756 -94.933262)
						(mid 96.269556 -94.933262)
						(end 98.123756 -94.933262)
					)
				)
			)
		)
	)
	(footprint ""
		(layer "F.Cu")
		(at 12.319 -95.504 180)
		(property "Reference" "R537"
			(at 0 0 180)
			(layer "F.SilkS")
			(hide yes)
			(effects
				(font
					(size 1.27 1.27)
				)
			)
		)
		(property "Value" ""
			(at 0 0 180)
			(layer "F.Fab")
			(effects
				(font
					(size 1.27 1.27)
				)
			)
		)
		(duplicate_pad_numbers_are_jumpers no)
		(fp_line
			(start 0.7874 0.4064)
			(end -0.7874 0.4064)
			(stroke
				(width 0.1524)
				(type default)
			)
			(layer "F.SilkS")
		)
		(fp_line
			(start 0.7874 -0.4064)
			(end 0.7874 0.4064)
			(stroke
				(width 0.1524)
				(type default)
			)
			(layer "F.SilkS")
		)
		(fp_line
			(start -0.7874 0.4064)
			(end -0.7874 -0.4064)
			(stroke
				(width 0.1524)
				(type default)
			)
			(layer "F.SilkS")
		)
		(fp_line
			(start -0.7874 -0.4064)
			(end 0.7874 -0.4064)
			(stroke
				(width 0.1524)
				(type default)
			)
			(layer "F.SilkS")
		)
		(fp_line
			(start 0.67945 0.3048)
			(end 0.120396 0.3048)
			(stroke
				(width 0.1)
				(type default)
			)
			(layer "F.Fab")
		)
		(fp_line
			(start 0.67945 -0.3048)
			(end 0.67945 0.3048)
			(stroke
				(width 0.1)
				(type default)
			)
			(layer "F.Fab")
		)
		(fp_line
			(start 0.12065 -0.2794)
			(end 0.12065 -0.3048)
			(stroke
				(width 0.1)
				(type default)
			)
			(layer "F.Fab")
		)
		(fp_line
			(start 0.12065 -0.3048)
			(end 0.67945 -0.3048)
			(stroke
				(width 0.1)
				(type default)
			)
			(layer "F.Fab")
		)
		(fp_line
			(start 0.120396 0.3048)
			(end 0.120396 0.2794)
			(stroke
				(width 0.1)
				(type default)
			)
			(layer "F.Fab")
		)
		(fp_line
			(start 0.120396 0.2794)
			(end -0.12065 0.2794)
			(stroke
				(width 0.1)
				(type default)
			)
			(layer "F.Fab")
		)
		(fp_line
			(start -0.12065 0.3048)
			(end -0.67945 0.3048)
			(stroke
				(width 0.1)
				(type default)
			)
			(layer "F.Fab")
		)
		(fp_line
			(start -0.12065 0.2794)
			(end -0.12065 0.3048)
			(stroke
				(width 0.1)
				(type default)
			)
			(layer "F.Fab")
		)
		(fp_line
			(start -0.12065 -0.2794)
			(end 0.12065 -0.2794)
			(stroke
				(width 0.1)
				(type default)
			)
			(layer "F.Fab")
		)
		(fp_line
			(start -0.12065 -0.305054)
			(end -0.12065 -0.2794)
			(stroke
				(width 0.1)
				(type default)
			)
			(layer "F.Fab")
		)
		(fp_line
			(start -0.67945 0.3048)
			(end -0.67945 -0.305054)
			(stroke
				(width 0.1)
				(type default)
			)
			(layer "F.Fab")
		)
		(fp_line
			(start -0.67945 -0.305054)
			(end -0.12065 -0.305054)
			(stroke
				(width 0.1)
				(type default)
			)
			(layer "F.Fab")
		)
		(pad "1" smd circle
			(at -0.40005 0 180)
			(size 0 0)
			(layers "F.Cu" "F.Mask" "F.Paste")
			(net "BMC_CPLD_GPIO_13_R2")
		)
		(pad "2" smd circle
			(at 0.40005 0 180)
			(size 0 0)
			(layers "F.Cu" "F.Mask" "F.Paste")
			(net "BMC_CPLD_GPIO_13")
		)
	)
	(footprint ""
		(layer "F.Cu")
		(at 12.30376 -64.54394 90)
		(property "Reference" "PC239"
			(at 0 0 90)
			(layer "F.SilkS")
			(hide yes)
			(effects
				(font
					(size 1.27 1.27)
				)
			)
		)
		(property "Value" ""
			(at 0 0 90)
			(layer "F.Fab")
			(effects
				(font
					(size 1.27 1.27)
				)
			)
		)
		(duplicate_pad_numbers_are_jumpers no)
		(fp_line
			(start 0.7874 -0.4064)
			(end 0.7874 0.4064)
			(stroke
				(width 0.1524)
				(type default)
			)
			(layer "F.SilkS")
		)
		(fp_line
			(start -0.7874 -0.4064)
			(end 0.7874 -0.4064)
			(stroke
				(width 0.1524)
				(type default)
			)
			(layer "F.SilkS")
		)
		(fp_line
			(start 0.7874 0.4064)
			(end -0.7874 0.4064)
			(stroke
				(width 0.1524)
				(type default)
			)
			(layer "F.SilkS")
		)
		(fp_line
			(start -0.7874 0.4064)
			(end -0.7874 -0.4064)
			(stroke
				(width 0.1524)
				(type default)
			)
			(layer "F.SilkS")
		)
		(fp_line
			(start -0.12065 -0.305054)
			(end -0.12065 -0.2794)
			(stroke
				(width 0.1)
				(type default)
			)
			(layer "F.Fab")
		)
		(fp_line
			(start -0.67945 -0.305054)
			(end -0.12065 -0.305054)
			(stroke
				(width 0.1)
				(type default)
			)
			(layer "F.Fab")
		)
		(fp_line
			(start 0.67945 -0.3048)
			(end 0.67945 0.3048)
			(stroke
				(width 0.1)
				(type default)
			)
			(layer "F.Fab")
		)
		(fp_line
			(start 0.12065 -0.3048)
			(end 0.67945 -0.3048)
			(stroke
				(width 0.1)
				(type default)
			)
			(layer "F.Fab")
		)
		(fp_line
			(start 0.12065 -0.2794)
			(end 0.12065 -0.3048)
			(stroke
				(width 0.1)
				(type default)
			)
			(layer "F.Fab")
		)
		(fp_line
			(start -0.12065 -0.2794)
			(end 0.12065 -0.2794)
			(stroke
				(width 0.1)
				(type default)
			)
			(layer "F.Fab")
		)
		(fp_line
			(start 0.120396 0.2794)
			(end -0.12065 0.2794)
			(stroke
				(width 0.1)
				(type default)
			)
			(layer "F.Fab")
		)
		(fp_line
			(start -0.12065 0.2794)
			(end -0.12065 0.3048)
			(stroke
				(width 0.1)
				(type default)
			)
			(layer "F.Fab")
		)
		(fp_line
			(start 0.67945 0.3048)
			(end 0.120396 0.3048)
			(stroke
				(width 0.1)
				(type default)
			)
			(layer "F.Fab")
		)
		(fp_line
			(start 0.120396 0.3048)
			(end 0.120396 0.2794)
			(stroke
				(width 0.1)
				(type default)
			)
			(layer "F.Fab")
		)
		(fp_line
			(start -0.12065 0.3048)
			(end -0.67945 0.3048)
			(stroke
				(width 0.1)
				(type default)
			)
			(layer "F.Fab")
		)
		(fp_line
			(start -0.67945 0.3048)
			(end -0.67945 -0.305054)
			(stroke
				(width 0.1)
				(type default)
			)
			(layer "F.Fab")
		)
		(pad "1" smd circle
			(at -0.40005 0 90)
			(size 0 0)
			(layers "F.Cu" "F.Mask" "F.Paste")
			(net "P3V3_AUX_FB_RC")
		)
		(pad "2" smd circle
			(at 0.40005 0 90)
			(size 0 0)
			(layers "F.Cu" "F.Mask" "F.Paste")
			(net "P3V3_AUX")
		)
	)
	(footprint ""
		(layer "F.Cu")
		(at 11.6586 -63.1952 180)
		(property "Reference" "R381"
			(at 0 0 180)
			(layer "F.SilkS")
			(hide yes)
			(effects
				(font
					(size 1.27 1.27)
				)
			)
		)
		(property "Value" ""
			(at 0 0 180)
			(layer "F.Fab")
			(effects
				(font
					(size 1.27 1.27)
				)
			)
		)
		(duplicate_pad_numbers_are_jumpers no)
		(fp_line
			(start 0.7874 0.4064)
			(end -0.7874 0.4064)
			(stroke
				(width 0.1524)
				(type default)
			)
			(layer "F.SilkS")
		)
		(fp_line
			(start 0.7874 -0.4064)
			(end 0.7874 0.4064)
			(stroke
				(width 0.1524)
				(type default)
			)
			(layer "F.SilkS")
		)
		(fp_line
			(start -0.7874 0.4064)
			(end -0.7874 -0.4064)
			(stroke
				(width 0.1524)
				(type default)
			)
			(layer "F.SilkS")
		)
		(fp_line
			(start -0.7874 -0.4064)
			(end 0.7874 -0.4064)
			(stroke
				(width 0.1524)
				(type default)
			)
			(layer "F.SilkS")
		)
		(fp_line
			(start 0.67945 0.3048)
			(end 0.120396 0.3048)
			(stroke
				(width 0.1)
				(type default)
			)
			(layer "F.Fab")
		)
		(fp_line
			(start 0.67945 -0.3048)
			(end 0.67945 0.3048)
			(stroke
				(width 0.1)
				(type default)
			)
			(layer "F.Fab")
		)
		(fp_line
			(start 0.12065 -0.2794)
			(end 0.12065 -0.3048)
			(stroke
				(width 0.1)
				(type default)
			)
			(layer "F.Fab")
		)
		(fp_line
			(start 0.12065 -0.3048)
			(end 0.67945 -0.3048)
			(stroke
				(width 0.1)
				(type default)
			)
			(layer "F.Fab")
		)
		(fp_line
			(start 0.120396 0.3048)
			(end 0.120396 0.2794)
			(stroke
				(width 0.1)
				(type default)
			)
			(layer "F.Fab")
		)
		(fp_line
			(start 0.120396 0.2794)
			(end -0.12065 0.2794)
			(stroke
				(width 0.1)
				(type default)
			)
			(layer "F.Fab")
		)
		(fp_line
			(start -0.12065 0.3048)
			(end -0.67945 0.3048)
			(stroke
				(width 0.1)
				(type default)
			)
			(layer "F.Fab")
		)
		(fp_line
			(start -0.12065 0.2794)
			(end -0.12065 0.3048)
			(stroke
				(width 0.1)
				(type default)
			)
			(layer "F.Fab")
		)
		(fp_line
			(start -0.12065 -0.2794)
			(end 0.12065 -0.2794)
			(stroke
				(width 0.1)
				(type default)
			)
			(layer "F.Fab")
		)
		(fp_line
			(start -0.12065 -0.305054)
			(end -0.12065 -0.2794)
			(stroke
				(width 0.1)
				(type default)
			)
			(layer "F.Fab")
		)
		(fp_line
			(start -0.67945 0.3048)
			(end -0.67945 -0.305054)
			(stroke
				(width 0.1)
				(type default)
			)
			(layer "F.Fab")
		)
		(fp_line
			(start -0.67945 -0.305054)
			(end -0.12065 -0.305054)
			(stroke
				(width 0.1)
				(type default)
			)
			(layer "F.Fab")
		)
		(pad "1" smd circle
			(at -0.40005 0 180)
			(size 0 0)
			(layers "F.Cu" "F.Mask" "F.Paste")
			(net "EN_P3V3")
		)
		(pad "2" smd circle
			(at 0.40005 0 180)
			(size 0 0)
			(layers "F.Cu" "F.Mask" "F.Paste")
			(net "PWRGD_EN_P3V3_R")
		)
	)
	(footprint ""
		(layer "F.Cu")
		(at 29.2608 -32.639)
		(property "Reference" "L30"
			(at 0 0 0)
			(layer "F.SilkS")
			(hide yes)
			(effects
				(font
					(size 1.27 1.27)
				)
			)
		)
		(property "Value" ""
			(at 0 0 0)
			(layer "F.Fab")
			(effects
				(font
					(size 1.27 1.27)
				)
			)
		)
		(duplicate_pad_numbers_are_jumpers no)
		(fp_line
			(start -1.27 -0.5842)
			(end 1.27 -0.5842)
			(stroke
				(width 0.1524)
				(type default)
			)
			(layer "F.SilkS")
		)
		(fp_line
			(start -1.27 -0.5588)
			(end -1.27 -0.5842)
			(stroke
				(width 0.1524)
				(type default)
			)
			(layer "F.SilkS")
		)
		(fp_line
			(start -1.27 0.5842)
			(end -1.27 -0.5842)
			(stroke
				(width 0.1524)
				(type default)
			)
			(layer "F.SilkS")
		)
		(fp_line
			(start -0.127 0.5842)
			(end -0.127 -0.5842)
			(stroke
				(width 0.1524)
				(type default)
			)
			(layer "F.SilkS")
		)
		(fp_line
			(start 0.127 0.5842)
			(end 0.127 -0.5842)
			(stroke
				(width 0.1524)
				(type default)
			)
			(layer "F.SilkS")
		)
		(fp_line
			(start 1.27 0.5842)
			(end -1.27 0.5842)
			(stroke
				(width 0.1524)
				(type default)
			)
			(layer "F.SilkS")
		)
		(fp_line
			(start 1.27 0.5842)
			(end 1.27 -0.5842)
			(stroke
				(width 0.1524)
				(type default)
			)
			(layer "F.SilkS")
		)
		(fp_line
			(start -1.194308 -0.406654)
			(end -0.9144 -0.406654)
			(stroke
				(width 0.1)
				(type default)
			)
			(layer "F.Fab")
		)
		(fp_line
			(start -1.194308 0.406654)
			(end -1.194308 -0.406654)
			(stroke
				(width 0.1)
				(type default)
			)
			(layer "F.Fab")
		)
		(fp_line
			(start -0.9144 -0.508)
			(end 0.9144 -0.508)
			(stroke
				(width 0.1)
				(type default)
			)
			(layer "F.Fab")
		)
		(fp_line
			(start -0.9144 -0.406654)
			(end -0.9144 -0.508)
			(stroke
				(width 0.1)
				(type default)
			)
			(layer "F.Fab")
		)
		(fp_line
			(start -0.9144 0.406654)
			(end -1.194308 0.406654)
			(stroke
				(width 0.1)
				(type default)
			)
			(layer "F.Fab")
		)
		(fp_line
			(start -0.9144 0.508)
			(end -0.9144 0.406654)
			(stroke
				(width 0.1)
				(type default)
			)
			(layer "F.Fab")
		)
		(fp_line
			(start 0.9144 -0.508)
			(end 0.9144 -0.406654)
			(stroke
				(width 0.1)
				(type default)
			)
			(layer "F.Fab")
		)
		(fp_line
			(start 0.9144 -0.406654)
			(end 1.1938 -0.406654)
			(stroke
				(width 0.1)
				(type default)
			)
			(layer "F.Fab")
		)
		(fp_line
			(start 0.9144 0.4064)
			(end 0.9144 0.508)
			(stroke
				(width 0.1)
				(type default)
			)
			(layer "F.Fab")
		)
		(fp_line
			(start 0.9144 0.508)
			(end -0.9144 0.508)
			(stroke
				(width 0.1)
				(type default)
			)
			(layer "F.Fab")
		)
		(fp_line
			(start 1.1938 -0.406654)
			(end 1.1938 0.4064)
			(stroke
				(width 0.1)
				(type default)
			)
			(layer "F.Fab")
		)
		(fp_line
			(start 1.1938 0.4064)
			(end 0.9144 0.4064)
			(stroke
				(width 0.1)
				(type default)
			)
			(layer "F.Fab")
		)
		(pad "1" smd rect
			(at -0.7366 0 270)
			(size 0.7112 0.8128)
			(layers "F.Cu" "F.Mask" "F.Paste")
			(net "V_DACR")
		)
		(pad "2" smd rect
			(at 0.7366 0 270)
			(size 0.7112 0.8128)
			(layers "F.Cu" "F.Mask" "F.Paste")
			(net "V_DACR_IO")
		)
	)
)
